# T6G (Grand Teton) — schematic netlist excerpt (pin names and nets, part order shuffled) for the footprints in the layout excerpt that follows; sources: Cadence DE-HDL packaged netlist, KiCad conversion of 04192023_DAF0TMB3IC0_F0TG_MB_C_brd_V02_OCP.brd

PU42  RAA229620GNPHA0  RAA229620GNP#HA0 IC  pkg QFN48_TH_0-4_6X6XH  page 193
  PWM0  = PVDDCR_SOC_P0_PWM1
  PWM1  = PVDDCR_SOC_P0_PWM2
  PWM2  = PVDDCR_SOC_P0_PWM3
  PWM3  = NC_PVDDCR_CPU0_P0_PWM9
  PWM4  = NC_PVDDCR_CPU0_P0_PWM8
  PWM5  = NC_PVDDCR_CPU0_P0_PWM7
  PWM6  = PVDDCR_CPU0_P0_PWM6
  PWM7  = PVDDCR_CPU0_P0_PWM5
  PWM8  = PVDDCR_CPU0_P0_PWM4
  PWM9  = PVDDCR_CPU0_P0_PWM3
  PWM10  = PVDDCR_CPU0_P0_PWM2
  PWM11  = PVDDCR_CPU0_P0_PWM1
  PMSDA  = PVDDCR_CPU0_P0_PMSDA_R
  PMSCL  = PVDDCR_CPU0_P0_PMSCL_R
  NPMALERT  = PVDDCR_CPU0_P0_PMALERT_R
  PG0  = PWRGD_PVDDCR_CPU0_P0_R
  EN0  = PVDDCR_CPU0_P0_EN_R
  RESET_L  = PVDDCR_CPU0_P0_RESET_N_R
  VDDIO  = PVDD18_S5_P0
  PG1  = PWRGD_PVDDCR_SOC_P0_R
  SVD  = SVID_PVDDCR_CPU0_P0_SVD_R1
  SVC  = SVID_PVDDCR_CPU0_P0_SVC_R1
  SVTO  = SVID_PVDDCR_CPU0_P0_SVTO_R
  SVTI  = SVID_PVDDCR_CPU0_P0_SVTI_R
  VSEN0  = VSENSE_PVDDCR_CPU0_P0_VSEN0
  RGND0  = VSENSE_VSS_SENSE_A_P0
  CS11  = PVDDCR_CPU0_P0_IMON1
  CS10  = PVDDCR_CPU0_P0_IMON2
  CS9  = PVDDCR_CPU0_P0_IMON3
  CS8  = PVDDCR_CPU0_P0_IMON4
  CS7  = PVDDCR_CPU0_P0_IMON5
  CS6  = PVDDCR_CPU0_P0_IMON6
  CS5  = NC_PVDDCR_CPU0_P0_IMON7
  CS4  = NC_PVDDCR_CPU0_P0_IMON8
  CS3  = NC_PVDDCR_CPU0_P0_IMON9
  CS2  = PVDDCR_SOC_P0_IMON3
  CS1  = PVDDCR_SOC_P0_IMON2
  CS0  = PVDDCR_SOC_P0_IMON1
  RGND1  = VSENSE_VSS_SENSE_A_P0
  VSEN1  = VSENSE_PVDDCR_SOC_P0_VSEN1
  OCP_L  = PVDDCR_CPU0_P0_OCP_N_R
  \en1||addr_cfg\  = PVDDCR_SOC_P0_EN//ADDR_CFG
  TEMP1  = PVDDCR_SOC_P0_TEMP1
  TEMP0  = PVDDCR_CPU0_P0_TEMP0
  \vmon||iinsen\  = PVDDCR_CPU0_P0_VMON
  VINSEN  = PVDDCR_CPU0_P0_VINSEN
  VCC  = PVDDCR_CPU0_P0_VCC
  VCCS  = PVDDCR_CPU0_P0_VCCS
  TH_GND  = GND

(kicad_pcb
	(version 20260206)
	(generator "pcbnew")
	(generator_version "10.0")
	(general
		(thickness 1.6)
		(legacy_teardrops no)
	)
	(paper "A4")
	(title_block
		(title "04192023_DAF0TMB3IC0_F0TG_MB_C_brd_V02_OCP.brd")
		(comment 1 "Grand Teton / footprint 5338 of 8354 (PU42), pads 42-49 of 49")
	)
	(layers
		(0 "F.Cu" signal "TOP")
		(4 "In1.Cu" signal "GND")
		(6 "In2.Cu" signal "IN1")
		(8 "In3.Cu" signal "GND1")
		(10 "In4.Cu" signal "IN2")
		(12 "In5.Cu" signal "GND2")
		(14 "In6.Cu" signal "IN3")
		(16 "In7.Cu" signal "GND3")
		(18 "In8.Cu" signal "VCC")
		(20 "In9.Cu" signal "VCC1")
		(22 "In10.Cu" signal "GND4")
		(24 "In11.Cu" signal "IN4")
		(26 "In12.Cu" signal "GND5")
		(28 "In13.Cu" signal "IN5")
		(30 "In14.Cu" signal "GND6")
		(32 "In15.Cu" signal "IN6")
		(34 "In16.Cu" signal "GND7")
		(2 "B.Cu" signal "BOTTOM")
		(9 "F.Adhes" user "F.Adhesive")
		(11 "B.Adhes" user "B.Adhesive")
		(13 "F.Paste" user "Package Geometry/Pastemask Top")
		(15 "B.Paste" user "Package Geometry/Pastemask Bottom")
		(5 "F.SilkS" user "Ref Des/Silkscreen Top")
		(7 "B.SilkS" user "Ref Des/Silkscreen Bottom")
		(1 "F.Mask" user "Board Geometry/Soldermask Top")
		(3 "B.Mask" user "Board Geometry/Soldermask Bottom")
		(17 "Dwgs.User" user "User.Drawings")
		(19 "Cmts.User" user "User.Comments")
		(21 "Eco1.User" user "User.Eco1")
		(23 "Eco2.User" user "User.Eco2")
		(25 "Edge.Cuts" user "Board Geometry/Outline")
		(27 "Margin" user)
		(31 "F.CrtYd" user "Package Geometry/Place Bound Top")
		(29 "B.CrtYd" user "Package Geometry/Place Bound Bottom")
		(35 "F.Fab" user "Ref Des/Assembly Top")
		(33 "B.Fab" user "Ref Des/Assembly Bottom")
	)
	(footprint ""
		(layer "B.Cu")
		(at 378.398278 -142.361158 -90)
		(property "Reference" "PU42"
			(at 5.846572 1.250696 0)
			(unlocked yes)
			(layer "B.SilkS")
			(effects
				(font
					(size 0.7874 0.5842)
					(thickness 0.1524)
				)
				(justify mirror)
			)
		)
		(property "Value" ""
			(at 0 0 90)
			(layer "B.Fab")
			(effects
				(font
					(size 1.27 1.27)
				)
				(justify mirror)
			)
		)
		(duplicate_pad_numbers_are_jumpers no)
		(pad "42" smd rect
			(at -0.199898 -2.875026 90)
			(size 0.1778 0.6604)
			(layers "B.Cu" "B.Mask" "B.Paste")
			(net "PVDDCR_SOC_P0_EN//ADDR_CFG")
		)
		(pad "43" smd rect
			(at 0.199898 -2.875026 90)
			(size 0.1778 0.6604)
			(layers "B.Cu" "B.Mask" "B.Paste")
			(net "PVDDCR_SOC_P0_TEMP1")
		)
		(pad "44" smd rect
			(at 0.599948 -2.875026 90)
			(size 0.1778 0.6604)
			(layers "B.Cu" "B.Mask" "B.Paste")
			(net "PVDDCR_CPU0_P0_TEMP0")
		)
		(pad "45" smd rect
			(at 0.999998 -2.875026 90)
			(size 0.1778 0.6604)
			(layers "B.Cu" "B.Mask" "B.Paste")
			(net "PVDDCR_CPU0_P0_VMON")
		)
		(pad "46" smd rect
			(at 1.400048 -2.875026 90)
			(size 0.1778 0.6604)
			(layers "B.Cu" "B.Mask" "B.Paste")
			(net "PVDDCR_CPU0_P0_VINSEN")
		)
		(pad "47" smd rect
			(at 1.800098 -2.875026 90)
			(size 0.1778 0.6604)
			(layers "B.Cu" "B.Mask" "B.Paste")
			(net "PVDDCR_CPU0_P0_VCC")
		)
		(pad "48" smd rect
			(at 2.199894 -2.875026 90)
			(size 0.1778 0.6604)
			(layers "B.Cu" "B.Mask" "B.Paste")
			(net "PVDDCR_CPU0_P0_VCCS")
		)
		(pad "TH" smd rect
			(at 0 0 90)
			(size 4.4196 4.4196)
			(layers "B.Cu" "B.Mask" "B.Paste")
			(net "GND")
		)
	)
)
